(kicad_pcb
	(version 20260206)
	(generator "pcbnew")
	(generator_version "10.0")
	(general
		(thickness 1.6)
		(legacy_teardrops no)
	)
	(paper "A4")
	(title_block
		(title "04192023_DAF0TMB3IC0_F0TG_MB_C_brd_V02_OCP.brd")
		(comment 1 "Grand Teton / footprints 1608-1614 of 8354")
	)
	(layers
		(0 "F.Cu" signal "TOP")
		(4 "In1.Cu" signal "GND")
		(6 "In2.Cu" signal "IN1")
		(8 "In3.Cu" signal "GND1")
		(10 "In4.Cu" signal "IN2")
		(12 "In5.Cu" signal "GND2")
		(14 "In6.Cu" signal "IN3")
		(16 "In7.Cu" signal "GND3")
		(18 "In8.Cu" signal "VCC")
		(20 "In9.Cu" signal "VCC1")
		(22 "In10.Cu" signal "GND4")
		(24 "In11.Cu" signal "IN4")
		(26 "In12.Cu" signal "GND5")
		(28 "In13.Cu" signal "IN5")
		(30 "In14.Cu" signal "GND6")
		(32 "In15.Cu" signal "IN6")
		(34 "In16.Cu" signal "GND7")
		(2 "B.Cu" signal "BOTTOM")
		(9 "F.Adhes" user "F.Adhesive")
		(11 "B.Adhes" user "B.Adhesive")
		(13 "F.Paste" user "Package Geometry/Pastemask Top")
		(15 "B.Paste" user "Package Geometry/Pastemask Bottom")
		(5 "F.SilkS" user "Ref Des/Silkscreen Top")
		(7 "B.SilkS" user "Ref Des/Silkscreen Bottom")
		(1 "F.Mask" user "Board Geometry/Soldermask Top")
		(3 "B.Mask" user "Board Geometry/Soldermask Bottom")
		(17 "Dwgs.User" user "User.Drawings")
		(19 "Cmts.User" user "User.Comments")
		(21 "Eco1.User" user "User.Eco1")
		(23 "Eco2.User" user "User.Eco2")
		(25 "Edge.Cuts" user "Board Geometry/Outline")
		(27 "Margin" user)
		(31 "F.CrtYd" user "Package Geometry/Place Bound Top")
		(29 "B.CrtYd" user "Package Geometry/Place Bound Bottom")
		(35 "F.Fab" user "Ref Des/Assembly Top")
		(33 "B.Fab" user "Ref Des/Assembly Bottom")
	)
	(footprint ""
		(layer "F.Cu")
		(at 42.3164 -396.0368 -90)
		(property "Reference" "L4"
			(at -3.60553 2.3114 0)
			(unlocked yes)
			(layer "F.SilkS")
			(effects
				(font
					(size 0.7874 0.5842)
					(thickness 0.1524)
				)
				(justify left)
			)
		)
		(property "Value" ""
			(at 0 0 270)
			(layer "F.Fab")
			(effects
				(font
					(size 1.27 1.27)
				)
			)
		)
		(duplicate_pad_numbers_are_jumpers no)
		(fp_line
			(start -2.249932 2.249932)
			(end -2.249932 1.3843)
			(stroke
				(width 0.1524)
				(type default)
			)
			(layer "F.SilkS")
		)
		(fp_line
			(start 2.249932 2.249932)
			(end -2.249932 2.249932)
			(stroke
				(width 0.1524)
				(type default)
			)
			(layer "F.SilkS")
		)
		(fp_line
			(start 2.249932 1.3843)
			(end 2.249932 2.249932)
			(stroke
				(width 0.1524)
				(type default)
			)
			(layer "F.SilkS")
		)
		(fp_line
			(start -2.249932 -1.3843)
			(end -2.249932 -2.249932)
			(stroke
				(width 0.1524)
				(type default)
			)
			(layer "F.SilkS")
		)
		(fp_line
			(start -2.249932 -2.249932)
			(end 2.249932 -2.249932)
			(stroke
				(width 0.1524)
				(type default)
			)
			(layer "F.SilkS")
		)
		(fp_line
			(start 2.249932 -2.249932)
			(end 2.249932 -1.3843)
			(stroke
				(width 0.1524)
				(type default)
			)
			(layer "F.SilkS")
		)
		(fp_line
			(start -2.249932 2.249932)
			(end -2.249932 -2.249932)
			(stroke
				(width 0.1)
				(type default)
			)
			(layer "F.Fab")
		)
		(fp_line
			(start 2.249932 2.249932)
			(end -2.249932 2.249932)
			(stroke
				(width 0.1)
				(type default)
			)
			(layer "F.Fab")
		)
		(fp_line
			(start -2.249932 -2.249932)
			(end 2.249932 -2.249932)
			(stroke
				(width 0.1)
				(type default)
			)
			(layer "F.Fab")
		)
		(fp_line
			(start 2.249932 -2.249932)
			(end 2.249932 2.249932)
			(stroke
				(width 0.1)
				(type default)
			)
			(layer "F.Fab")
		)
		(pad "1" smd rect
			(at -1.82499 0 270)
			(size 1.0668 2.5146)
			(layers "F.Cu" "F.Mask" "F.Paste")
			(net "P0V9_CPU1_RT_2D")
		)
		(pad "2" smd rect
			(at 1.82499 0 270)
			(size 1.0668 2.5146)
			(layers "F.Cu" "F.Mask" "F.Paste")
			(net "P0V9_CPU1_RT0_2A")
		)
	)
	(footprint ""
		(layer "F.Cu")
		(at 187.563506 -351.319084 -90)
		(property "Reference" "PC508_11P1_2"
			(at 0 0 270)
			(layer "F.SilkS")
			(hide yes)
			(effects
				(font
					(size 1.27 1.27)
				)
			)
		)
		(property "Value" ""
			(at 0 0 270)
			(layer "F.Fab")
			(effects
				(font
					(size 1.27 1.27)
				)
			)
		)
		(duplicate_pad_numbers_are_jumpers no)
		(fp_line
			(start -0.7874 0.4064)
			(end -0.7874 -0.4064)
			(stroke
				(width 0.1524)
				(type default)
			)
			(layer "F.SilkS")
		)
		(fp_line
			(start 0.7874 0.4064)
			(end -0.7874 0.4064)
			(stroke
				(width 0.1524)
				(type default)
			)
			(layer "F.SilkS")
		)
		(fp_line
			(start -0.7874 -0.4064)
			(end 0.7874 -0.4064)
			(stroke
				(width 0.1524)
				(type default)
			)
			(layer "F.SilkS")
		)
		(fp_line
			(start 0.7874 -0.4064)
			(end 0.7874 0.4064)
			(stroke
				(width 0.1524)
				(type default)
			)
			(layer "F.SilkS")
		)
		(fp_line
			(start -0.67945 0.3048)
			(end -0.67945 -0.305054)
			(stroke
				(width 0.1)
				(type default)
			)
			(layer "F.Fab")
		)
		(fp_line
			(start -0.12065 0.3048)
			(end -0.67945 0.3048)
			(stroke
				(width 0.1)
				(type default)
			)
			(layer "F.Fab")
		)
		(fp_line
			(start 0.120396 0.3048)
			(end 0.120396 0.2794)
			(stroke
				(width 0.1)
				(type default)
			)
			(layer "F.Fab")
		)
		(fp_line
			(start 0.67945 0.3048)
			(end 0.120396 0.3048)
			(stroke
				(width 0.1)
				(type default)
			)
			(layer "F.Fab")
		)
		(fp_line
			(start -0.12065 0.2794)
			(end -0.12065 0.3048)
			(stroke
				(width 0.1)
				(type default)
			)
			(layer "F.Fab")
		)
		(fp_line
			(start 0.120396 0.2794)
			(end -0.12065 0.2794)
			(stroke
				(width 0.1)
				(type default)
			)
			(layer "F.Fab")
		)
		(fp_line
			(start -0.12065 -0.2794)
			(end 0.12065 -0.2794)
			(stroke
				(width 0.1)
				(type default)
			)
			(layer "F.Fab")
		)
		(fp_line
			(start 0.12065 -0.2794)
			(end 0.12065 -0.3048)
			(stroke
				(width 0.1)
				(type default)
			)
			(layer "F.Fab")
		)
		(fp_line
			(start 0.12065 -0.3048)
			(end 0.67945 -0.3048)
			(stroke
				(width 0.1)
				(type default)
			)
			(layer "F.Fab")
		)
		(fp_line
			(start 0.67945 -0.3048)
			(end 0.67945 0.3048)
			(stroke
				(width 0.1)
				(type default)
			)
			(layer "F.Fab")
		)
		(fp_line
			(start -0.67945 -0.305054)
			(end -0.12065 -0.305054)
			(stroke
				(width 0.1)
				(type default)
			)
			(layer "F.Fab")
		)
		(fp_line
			(start -0.12065 -0.305054)
			(end -0.12065 -0.2794)
			(stroke
				(width 0.1)
				(type default)
			)
			(layer "F.Fab")
		)
		(pad "1" smd circle
			(at -0.40005 0 270)
			(size 0 0)
			(layers "F.Cu" "F.Mask" "F.Paste")
			(net "PVDD11_S3_P1_PVCC")
		)
		(pad "2" smd circle
			(at 0.40005 0 270)
			(size 0 0)
			(layers "F.Cu" "F.Mask" "F.Paste")
			(net "GND")
		)
	)
	(footprint ""
		(layer "F.Cu")
		(at 65.3796 -14.8336 180)
		(property "Reference" "C1833"
			(at 0 0 180)
			(layer "F.SilkS")
			(hide yes)
			(effects
				(font
					(size 1.27 1.27)
				)
			)
		)
		(property "Value" ""
			(at 0 0 180)
			(layer "F.Fab")
			(effects
				(font
					(size 1.27 1.27)
				)
			)
		)
		(duplicate_pad_numbers_are_jumpers no)
		(fp_line
			(start 0.7874 0.4064)
			(end -0.7874 0.4064)
			(stroke
				(width 0.1524)
				(type default)
			)
			(layer "F.SilkS")
		)
		(fp_line
			(start 0.7874 -0.4064)
			(end 0.7874 0.4064)
			(stroke
				(width 0.1524)
				(type default)
			)
			(layer "F.SilkS")
		)
		(fp_line
			(start -0.7874 0.4064)
			(end -0.7874 -0.4064)
			(stroke
				(width 0.1524)
				(type default)
			)
			(layer "F.SilkS")
		)
		(fp_line
			(start -0.7874 -0.4064)
			(end 0.7874 -0.4064)
			(stroke
				(width 0.1524)
				(type default)
			)
			(layer "F.SilkS")
		)
		(fp_line
			(start 0.67945 0.3048)
			(end 0.120396 0.3048)
			(stroke
				(width 0.1)
				(type default)
			)
			(layer "F.Fab")
		)
		(fp_line
			(start 0.67945 -0.3048)
			(end 0.67945 0.3048)
			(stroke
				(width 0.1)
				(type default)
			)
			(layer "F.Fab")
		)
		(fp_line
			(start 0.12065 -0.2794)
			(end 0.12065 -0.3048)
			(stroke
				(width 0.1)
				(type default)
			)
			(layer "F.Fab")
		)
		(fp_line
			(start 0.12065 -0.3048)
			(end 0.67945 -0.3048)
			(stroke
				(width 0.1)
				(type default)
			)
			(layer "F.Fab")
		)
		(fp_line
			(start 0.120396 0.3048)
			(end 0.120396 0.2794)
			(stroke
				(width 0.1)
				(type default)
			)
			(layer "F.Fab")
		)
		(fp_line
			(start 0.120396 0.2794)
			(end -0.12065 0.2794)
			(stroke
				(width 0.1)
				(type default)
			)
			(layer "F.Fab")
		)
		(fp_line
			(start -0.12065 0.3048)
			(end -0.67945 0.3048)
			(stroke
				(width 0.1)
				(type default)
			)
			(layer "F.Fab")
		)
		(fp_line
			(start -0.12065 0.2794)
			(end -0.12065 0.3048)
			(stroke
				(width 0.1)
				(type default)
			)
			(layer "F.Fab")
		)
		(fp_line
			(start -0.12065 -0.2794)
			(end 0.12065 -0.2794)
			(stroke
				(width 0.1)
				(type default)
			)
			(layer "F.Fab")
		)
		(fp_line
			(start -0.12065 -0.305054)
			(end -0.12065 -0.2794)
			(stroke
				(width 0.1)
				(type default)
			)
			(layer "F.Fab")
		)
		(fp_line
			(start -0.67945 0.3048)
			(end -0.67945 -0.305054)
			(stroke
				(width 0.1)
				(type default)
			)
			(layer "F.Fab")
		)
		(fp_line
			(start -0.67945 -0.305054)
			(end -0.12065 -0.305054)
			(stroke
				(width 0.1)
				(type default)
			)
			(layer "F.Fab")
		)
		(pad "1" smd circle
			(at -0.40005 0 180)
			(size 0 0)
			(layers "F.Cu" "F.Mask" "F.Paste")
			(net "P12V_OCP_V3_2_R")
		)
		(pad "2" smd circle
			(at 0.40005 0 180)
			(size 0 0)
			(layers "F.Cu" "F.Mask" "F.Paste")
			(net "GND")
		)
	)
	(footprint ""
		(layer "F.Cu")
		(at 204.992986 -98.244914)
		(property "Reference" "C1059"
			(at 0 0 0)
			(layer "F.SilkS")
			(hide yes)
			(effects
				(font
					(size 1.27 1.27)
				)
			)
		)
		(property "Value" ""
			(at 0 0 0)
			(layer "F.Fab")
			(effects
				(font
					(size 1.27 1.27)
				)
			)
		)
		(duplicate_pad_numbers_are_jumpers no)
		(fp_line
			(start -0.7874 -0.4064)
			(end 0.7874 -0.4064)
			(stroke
				(width 0.1524)
				(type default)
			)
			(layer "F.SilkS")
		)
		(fp_line
			(start -0.7874 0.4064)
			(end -0.7874 -0.4064)
			(stroke
				(width 0.1524)
				(type default)
			)
			(layer "F.SilkS")
		)
		(fp_line
			(start 0.7874 -0.4064)
			(end 0.7874 0.4064)
			(stroke
				(width 0.1524)
				(type default)
			)
			(layer "F.SilkS")
		)
		(fp_line
			(start 0.7874 0.4064)
			(end -0.7874 0.4064)
			(stroke
				(width 0.1524)
				(type default)
			)
			(layer "F.SilkS")
		)
		(fp_line
			(start -0.67945 -0.305054)
			(end -0.12065 -0.305054)
			(stroke
				(width 0.1)
				(type default)
			)
			(layer "F.Fab")
		)
		(fp_line
			(start -0.67945 0.3048)
			(end -0.67945 -0.305054)
			(stroke
				(width 0.1)
				(type default)
			)
			(layer "F.Fab")
		)
		(fp_line
			(start -0.12065 -0.305054)
			(end -0.12065 -0.2794)
			(stroke
				(width 0.1)
				(type default)
			)
			(layer "F.Fab")
		)
		(fp_line
			(start -0.12065 -0.2794)
			(end 0.12065 -0.2794)
			(stroke
				(width 0.1)
				(type default)
			)
			(layer "F.Fab")
		)
		(fp_line
			(start -0.12065 0.2794)
			(end -0.12065 0.3048)
			(stroke
				(width 0.1)
				(type default)
			)
			(layer "F.Fab")
		)
		(fp_line
			(start -0.12065 0.3048)
			(end -0.67945 0.3048)
			(stroke
				(width 0.1)
				(type default)
			)
			(layer "F.Fab")
		)
		(fp_line
			(start 0.120396 0.2794)
			(end -0.12065 0.2794)
			(stroke
				(width 0.1)
				(type default)
			)
			(layer "F.Fab")
		)
		(fp_line
			(start 0.120396 0.3048)
			(end 0.120396 0.2794)
			(stroke
				(width 0.1)
				(type default)
			)
			(layer "F.Fab")
		)
		(fp_line
			(start 0.12065 -0.3048)
			(end 0.67945 -0.3048)
			(stroke
				(width 0.1)
				(type default)
			)
			(layer "F.Fab")
		)
		(fp_line
			(start 0.12065 -0.2794)
			(end 0.12065 -0.3048)
			(stroke
				(width 0.1)
				(type default)
			)
			(layer "F.Fab")
		)
		(fp_line
			(start 0.67945 -0.3048)
			(end 0.67945 0.3048)
			(stroke
				(width 0.1)
				(type default)
			)
			(layer "F.Fab")
		)
		(fp_line
			(start 0.67945 0.3048)
			(end 0.120396 0.3048)
			(stroke
				(width 0.1)
				(type default)
			)
			(layer "F.Fab")
		)
		(pad "1" smd circle
			(at -0.40005 0)
			(size 0 0)
			(layers "F.Cu" "F.Mask" "F.Paste")
			(net "P3V3_AUX")
		)
		(pad "2" smd circle
			(at 0.40005 0)
			(size 0 0)
			(layers "F.Cu" "F.Mask" "F.Paste")
			(net "GND")
		)
	)
	(footprint ""
		(layer "F.Cu")
		(at 179.71643 -92.664534 90)
		(property "Reference" "R6146"
			(at 0 0 90)
			(layer "F.SilkS")
			(hide yes)
			(effects
				(font
					(size 1.27 1.27)
				)
			)
		)
		(property "Value" ""
			(at 0 0 90)
			(layer "F.Fab")
			(effects
				(font
					(size 1.27 1.27)
				)
			)
		)
		(duplicate_pad_numbers_are_jumpers no)
		(fp_line
			(start 0.7874 -0.4064)
			(end 0.7874 0.4064)
			(stroke
				(width 0.1524)
				(type default)
			)
			(layer "F.SilkS")
		)
		(fp_line
			(start -0.7874 -0.4064)
			(end 0.7874 -0.4064)
			(stroke
				(width 0.1524)
				(type default)
			)
			(layer "F.SilkS")
		)
		(fp_line
			(start 0.7874 0.4064)
			(end -0.7874 0.4064)
			(stroke
				(width 0.1524)
				(type default)
			)
			(layer "F.SilkS")
		)
		(fp_line
			(start -0.7874 0.4064)
			(end -0.7874 -0.4064)
			(stroke
				(width 0.1524)
				(type default)
			)
			(layer "F.SilkS")
		)
		(fp_line
			(start -0.12065 -0.305054)
			(end -0.12065 -0.2794)
			(stroke
				(width 0.1)
				(type default)
			)
			(layer "F.Fab")
		)
		(fp_line
			(start -0.67945 -0.305054)
			(end -0.12065 -0.305054)
			(stroke
				(width 0.1)
				(type default)
			)
			(layer "F.Fab")
		)
		(fp_line
			(start 0.67945 -0.3048)
			(end 0.67945 0.3048)
			(stroke
				(width 0.1)
				(type default)
			)
			(layer "F.Fab")
		)
		(fp_line
			(start 0.12065 -0.3048)
			(end 0.67945 -0.3048)
			(stroke
				(width 0.1)
				(type default)
			)
			(layer "F.Fab")
		)
		(fp_line
			(start 0.12065 -0.2794)
			(end 0.12065 -0.3048)
			(stroke
				(width 0.1)
				(type default)
			)
			(layer "F.Fab")
		)
		(fp_line
			(start -0.12065 -0.2794)
			(end 0.12065 -0.2794)
			(stroke
				(width 0.1)
				(type default)
			)
			(layer "F.Fab")
		)
		(fp_line
			(start 0.120396 0.2794)
			(end -0.12065 0.2794)
			(stroke
				(width 0.1)
				(type default)
			)
			(layer "F.Fab")
		)
		(fp_line
			(start -0.12065 0.2794)
			(end -0.12065 0.3048)
			(stroke
				(width 0.1)
				(type default)
			)
			(layer "F.Fab")
		)
		(fp_line
			(start 0.67945 0.3048)
			(end 0.120396 0.3048)
			(stroke
				(width 0.1)
				(type default)
			)
			(layer "F.Fab")
		)
		(fp_line
			(start 0.120396 0.3048)
			(end 0.120396 0.2794)
			(stroke
				(width 0.1)
				(type default)
			)
			(layer "F.Fab")
		)
		(fp_line
			(start -0.12065 0.3048)
			(end -0.67945 0.3048)
			(stroke
				(width 0.1)
				(type default)
			)
			(layer "F.Fab")
		)
		(fp_line
			(start -0.67945 0.3048)
			(end -0.67945 -0.305054)
			(stroke
				(width 0.1)
				(type default)
			)
			(layer "F.Fab")
		)
		(pad "1" smd circle
			(at -0.40005 0 90)
			(size 0 0)
			(layers "F.Cu" "F.Mask" "F.Paste")
			(net "P1V8_AUX")
		)
		(pad "2" smd circle
			(at 0.40005 0 90)
			(size 0 0)
			(layers "F.Cu" "F.Mask" "F.Paste")
			(net "FAB_BMC_REV_ID2")
		)
	)
	(footprint ""
		(layer "F.Cu")
		(at 78.724506 -152.990804 90)
		(property "Reference" "PC152"
			(at 0 0 90)
			(layer "F.SilkS")
			(hide yes)
			(effects
				(font
					(size 1.27 1.27)
				)
			)
		)
		(property "Value" ""
			(at 0 0 90)
			(layer "F.Fab")
			(effects
				(font
					(size 1.27 1.27)
				)
			)
		)
		(duplicate_pad_numbers_are_jumpers no)
		(fp_line
			(start 1.524 -0.762)
			(end 1.524 0.762)
			(stroke
				(width 0.1524)
				(type default)
			)
			(layer "F.SilkS")
		)
		(fp_line
			(start -1.524 -0.762)
			(end 1.524 -0.762)
			(stroke
				(width 0.1524)
				(type default)
			)
			(layer "F.SilkS")
		)
		(fp_line
			(start 1.524 0.762)
			(end -1.524 0.762)
			(stroke
				(width 0.1524)
				(type default)
			)
			(layer "F.SilkS")
		)
		(fp_line
			(start -1.524 0.762)
			(end -1.524 -0.762)
			(stroke
				(width 0.1524)
				(type default)
			)
			(layer "F.SilkS")
		)
		(fp_line
			(start 1.1049 -0.724916)
			(end -1.1049 -0.724916)
			(stroke
				(width 0.1)
				(type default)
			)
			(layer "F.Fab")
		)
		(fp_line
			(start -1.1049 -0.724916)
			(end -1.1049 0.724916)
			(stroke
				(width 0.1)
				(type default)
			)
			(layer "F.Fab")
		)
		(fp_line
			(start 1.1049 0.724916)
			(end 1.1049 -0.724916)
			(stroke
				(width 0.1)
				(type default)
			)
			(layer "F.Fab")
		)
		(fp_line
			(start -1.1049 0.724916)
			(end 1.1049 0.724916)
			(stroke
				(width 0.1)
				(type default)
			)
			(layer "F.Fab")
		)
		(pad "1" smd rect
			(at -0.889 0 270)
			(size 1.016 1.27)
			(layers "F.Cu" "F.Mask" "F.Paste")
			(net "SW_P12V_AUX_PVDD18_S5_P1_FLT")
		)
		(pad "2" smd rect
			(at 0.889 0 270)
			(size 1.016 1.27)
			(layers "F.Cu" "F.Mask" "F.Paste")
			(net "GND")
		)
	)
	(footprint ""
		(layer "F.Cu")
		(at 382.320292 -378.95403 -90)
		(property "Reference" "C882"
			(at 0 0 270)
			(layer "F.SilkS")
			(hide yes)
			(effects
				(font
					(size 1.27 1.27)
				)
			)
		)
		(property "Value" ""
			(at 0 0 270)
			(layer "F.Fab")
			(effects
				(font
					(size 1.27 1.27)
				)
			)
		)
		(duplicate_pad_numbers_are_jumpers no)
		(fp_line
			(start -0.299974 0.150114)
			(end -0.299974 -0.150114)
			(stroke
				(width 0.1)
				(type default)
			)
			(layer "F.Fab")
		)
		(fp_line
			(start 0.299974 0.150114)
			(end -0.299974 0.150114)
			(stroke
				(width 0.1)
				(type default)
			)
			(layer "F.Fab")
		)
		(fp_line
			(start -0.299974 -0.150114)
			(end 0.299974 -0.150114)
			(stroke
				(width 0.1)
				(type default)
			)
			(layer "F.Fab")
		)
		(fp_line
			(start 0.299974 -0.150114)
			(end 0.299974 0.150114)
			(stroke
				(width 0.1)
				(type default)
			)
			(layer "F.Fab")
		)
		(pad "1" smd rect
			(at -0.2667 0 270)
			(size 0.3048 0.381)
			(layers "F.Cu" "F.Mask" "F.Paste")
			(net "P5E_CPU0_P3_TX_C_DN<9>")
		)
		(pad "2" smd rect
			(at 0.2667 0 270)
			(size 0.3048 0.381)
			(layers "F.Cu" "F.Mask" "F.Paste")
			(net "P5E_CPU0_P3_TX_DN<9>")
		)
	)
)
